(kicad_pcb
	(version 20260206)
	(generator "pcbnew")
	(generator_version "10.0")
	(general
		(thickness 1.6)
		(legacy_teardrops no)
	)
	(paper "A4")
	(title_block
		(title "03242023_DA0F0TMBIJ0_F0T_Motherboard_J_brd_V01_OCP.brd")
		(comment 1 "Grand Teton / footprint 3039 of 6105 (U2), pads 4652-4677 of 4677")
	)
	(layers
		(0 "F.Cu" signal "TOP")
		(4 "In1.Cu" signal "GND")
		(6 "In2.Cu" signal "IN1")
		(8 "In3.Cu" signal "GND1")
		(10 "In4.Cu" signal "IN2")
		(12 "In5.Cu" signal "GND2")
		(14 "In6.Cu" signal "IN3")
		(16 "In7.Cu" signal "GND3")
		(18 "In8.Cu" signal "VCC")
		(20 "In9.Cu" signal "VCC1")
		(22 "In10.Cu" signal "GND4")
		(24 "In11.Cu" signal "IN4")
		(26 "In12.Cu" signal "GND5")
		(28 "In13.Cu" signal "IN5")
		(30 "In14.Cu" signal "GND6")
		(32 "In15.Cu" signal "IN6")
		(34 "In16.Cu" signal "GND7")
		(2 "B.Cu" signal "BOTTOM")
		(9 "F.Adhes" user "F.Adhesive")
		(11 "B.Adhes" user "B.Adhesive")
		(13 "F.Paste" user "Package Geometry/Pastemask Top")
		(15 "B.Paste" user "Package Geometry/Pastemask Bottom")
		(5 "F.SilkS" user "Ref Des/Silkscreen Top")
		(7 "B.SilkS" user "Ref Des/Silkscreen Bottom")
		(1 "F.Mask" user "Board Geometry/Soldermask Top")
		(3 "B.Mask" user "Board Geometry/Soldermask Bottom")
		(17 "Dwgs.User" user "User.Drawings")
		(19 "Cmts.User" user "User.Comments")
		(21 "Eco1.User" user "User.Eco1")
		(23 "Eco2.User" user "User.Eco2")
		(25 "Edge.Cuts" user "Board Geometry/Outline")
		(27 "Margin" user)
		(31 "F.CrtYd" user "Package Geometry/Place Bound Top")
		(29 "B.CrtYd" user "Package Geometry/Place Bound Bottom")
		(35 "F.Fab" user "Ref Des/Assembly Top")
		(33 "B.Fab" user "Ref Des/Assembly Bottom")
	)
	(footprint ""
		(layer "F.Cu")
		(at 359.870248 -251.76988 90)
		(property "Reference" "U2"
			(at -74.416158 -44.488608 0)
			(unlocked yes)
			(layer "F.SilkS")
			(effects
				(font
					(size 1.6002 1.1938)
					(thickness 0.1524)
				)
				(justify left)
			)
		)
		(property "Value" ""
			(at 0 0 90)
			(layer "F.Fab")
			(effects
				(font
					(size 1.27 1.27)
				)
			)
		)
		(duplicate_pad_numbers_are_jumpers no)
		(pad "Y40" smd circle
			(at -5.68325 -18.146268 270)
			(size 0.4318 0.4318)
			(layers "F.Cu" "F.Mask" "F.Paste")
			(net "M_C_CPU0_SB_CA<5>")
		)
		(pad "Y42" smd circle
			(at -4.055618 -18.146268 270)
			(size 0.4318 0.4318)
			(layers "F.Cu" "F.Mask" "F.Paste")
			(net "GND")
		)
		(pad "Y44" smd circle
			(at -2.427732 -18.146268 270)
			(size 0.4318 0.4318)
			(layers "F.Cu" "F.Mask" "F.Paste")
			(net "M_B_CPU0_SA_CA<6>")
		)
		(pad "Y47" smd circle
			(at 1.613916 -18.036286 270)
			(size 0.4318 0.4318)
			(layers "F.Cu" "F.Mask" "F.Paste")
			(net "M_C_CPU0_SB_CA<1>")
		)
		(pad "Y49" smd circle
			(at 3.241802 -18.036286 270)
			(size 0.4318 0.4318)
			(layers "F.Cu" "F.Mask" "F.Paste")
			(net "GND")
		)
		(pad "Y51" smd circle
			(at 4.869434 -18.036286 270)
			(size 0.4318 0.4318)
			(layers "F.Cu" "F.Mask" "F.Paste")
			(net "M_C_CPU0_SA_CA<3>")
		)
		(pad "Y53" smd circle
			(at 6.49732 -18.036286 270)
			(size 0.4318 0.4318)
			(layers "F.Cu" "F.Mask" "F.Paste")
			(net "M_C_CPU0_SA_CS_N<3>")
		)
		(pad "Y55" smd circle
			(at 8.124952 -18.036286 270)
			(size 0.4318 0.4318)
			(layers "F.Cu" "F.Mask" "F.Paste")
			(net "GND")
		)
		(pad "Y57" smd circle
			(at 9.752838 -18.036286 270)
			(size 0.4318 0.4318)
			(layers "F.Cu" "F.Mask" "F.Paste")
			(net "M_B_CPU0_SA_DQ<30>")
		)
		(pad "Y59" smd circle
			(at 11.380724 -18.036286 270)
			(size 0.4318 0.4318)
			(layers "F.Cu" "F.Mask" "F.Paste")
			(net "M_B_CPU0_SA_DQ<27>")
		)
		(pad "Y61" smd circle
			(at 13.008356 -18.036286 270)
			(size 0.4318 0.4318)
			(layers "F.Cu" "F.Mask" "F.Paste")
			(net "GND")
		)
		(pad "Y63" smd circle
			(at 14.635988 -18.036286 270)
			(size 0.4318 0.4318)
			(layers "F.Cu" "F.Mask" "F.Paste")
			(net "M_C_CPU0_SA_DQ<22>")
		)
		(pad "Y65" smd circle
			(at 16.263874 -18.036286 270)
			(size 0.4318 0.4318)
			(layers "F.Cu" "F.Mask" "F.Paste")
			(net "M_C_CPU0_SA_DQ<19>")
		)
		(pad "Y67" smd circle
			(at 17.89176 -18.036286 270)
			(size 0.4318 0.4318)
			(layers "F.Cu" "F.Mask" "F.Paste")
			(net "GND")
		)
		(pad "Y69" smd circle
			(at 19.519392 -18.036286 270)
			(size 0.4318 0.4318)
			(layers "F.Cu" "F.Mask" "F.Paste")
			(net "M_B_CPU0_SA_DQ<14>")
		)
		(pad "Y71" smd circle
			(at 21.147278 -18.036286 270)
			(size 0.4318 0.4318)
			(layers "F.Cu" "F.Mask" "F.Paste")
			(net "M_B_CPU0_SA_DQ<11>")
		)
		(pad "Y73" smd circle
			(at 22.77491 -18.036286 270)
			(size 0.4318 0.4318)
			(layers "F.Cu" "F.Mask" "F.Paste")
			(net "GND")
		)
		(pad "Y75" smd circle
			(at 24.402796 -18.036286 270)
			(size 0.4318 0.4318)
			(layers "F.Cu" "F.Mask" "F.Paste")
			(net "M_C_CPU0_SA_DQ<6>")
		)
		(pad "Y77" smd circle
			(at 26.030682 -18.036286 270)
			(size 0.4318 0.4318)
			(layers "F.Cu" "F.Mask" "F.Paste")
			(net "M_C_CPU0_SA_DQ<3>")
		)
		(pad "Y79" smd circle
			(at 27.658314 -18.036286 270)
			(size 0.4318 0.4318)
			(layers "F.Cu" "F.Mask" "F.Paste")
			(net "PVCCFA_EHV_FIVRA_CPU0")
		)
		(pad "Y81" smd circle
			(at 29.2862 -18.036286 270)
			(size 0.4318 0.4318)
			(layers "F.Cu" "F.Mask" "F.Paste")
			(net "UPI_CPU0_CPU1_P2P2_DN<14>")
		)
		(pad "Y83" smd circle
			(at 30.914086 -18.036286 270)
			(size 0.4318 0.4318)
			(layers "F.Cu" "F.Mask" "F.Paste")
			(net "UPI_CPU0_CPU1_P2P2_DP<15>")
		)
		(pad "Y85" smd circle
			(at 32.541718 -18.036286 270)
			(size 0.4318 0.4318)
			(layers "F.Cu" "F.Mask" "F.Paste")
			(net "PVCCFA_EHV_FIVRA_CPU0")
		)
		(pad "Y87" smd circle
			(at 34.169604 -18.036286 270)
			(size 0.4318 0.4318)
			(layers "F.Cu" "F.Mask" "F.Paste")
			(net "P5E_CPU0_PE4_TX_DP<4>")
		)
		(pad "Y89" smd circle
			(at 35.797236 -18.036286 270)
			(size 0.4318 0.4318)
			(layers "F.Cu" "F.Mask" "F.Paste")
			(net "PVCCFA_EHV_FIVRA_CPU0")
		)
		(pad "Y91" smd oval
			(at 37.425122 -18.036286)
			(size 0.381 0.4826)
			(drill
				(offset 0 -0.0508)
			)
			(layers "F.Cu" "F.Mask" "F.Paste")
			(net "P5E_CPU0_PE4_RX_DN<4>")
		)
	)
)
